(kicad_pcb
	(version 20260206)
	(generator "pcbnew")
	(generator_version "10.0")
	(general
		(thickness 1.6)
		(legacy_teardrops no)
	)
	(paper "A4")
	(title_block
		(title "03242023_DA0F0TMBIJ0_F0T_Motherboard_J_brd_V01_OCP.brd")
		(comment 1 "Grand Teton / footprints 1369-1372 of 6105")
	)
	(layers
		(0 "F.Cu" signal "TOP")
		(4 "In1.Cu" signal "GND")
		(6 "In2.Cu" signal "IN1")
		(8 "In3.Cu" signal "GND1")
		(10 "In4.Cu" signal "IN2")
		(12 "In5.Cu" signal "GND2")
		(14 "In6.Cu" signal "IN3")
		(16 "In7.Cu" signal "GND3")
		(18 "In8.Cu" signal "VCC")
		(20 "In9.Cu" signal "VCC1")
		(22 "In10.Cu" signal "GND4")
		(24 "In11.Cu" signal "IN4")
		(26 "In12.Cu" signal "GND5")
		(28 "In13.Cu" signal "IN5")
		(30 "In14.Cu" signal "GND6")
		(32 "In15.Cu" signal "IN6")
		(34 "In16.Cu" signal "GND7")
		(2 "B.Cu" signal "BOTTOM")
		(9 "F.Adhes" user "F.Adhesive")
		(11 "B.Adhes" user "B.Adhesive")
		(13 "F.Paste" user "Package Geometry/Pastemask Top")
		(15 "B.Paste" user "Package Geometry/Pastemask Bottom")
		(5 "F.SilkS" user "Ref Des/Silkscreen Top")
		(7 "B.SilkS" user "Ref Des/Silkscreen Bottom")
		(1 "F.Mask" user "Board Geometry/Soldermask Top")
		(3 "B.Mask" user "Board Geometry/Soldermask Bottom")
		(17 "Dwgs.User" user "User.Drawings")
		(19 "Cmts.User" user "User.Comments")
		(21 "Eco1.User" user "User.Eco1")
		(23 "Eco2.User" user "User.Eco2")
		(25 "Edge.Cuts" user "Board Geometry/Outline")
		(27 "Margin" user)
		(31 "F.CrtYd" user "Package Geometry/Place Bound Top")
		(29 "B.CrtYd" user "Package Geometry/Place Bound Bottom")
		(35 "F.Fab" user "Ref Des/Assembly Top")
		(33 "B.Fab" user "Ref Des/Assembly Bottom")
	)
	(footprint ""
		(layer "F.Cu")
		(at 352.663252 -315.66739 90)
		(property "Reference" "PC322"
			(at 0 0 90)
			(layer "F.SilkS")
			(hide yes)
			(effects
				(font
					(size 1.27 1.27)
				)
			)
		)
		(property "Value" ""
			(at 0 0 90)
			(layer "F.Fab")
			(effects
				(font
					(size 1.27 1.27)
				)
			)
		)
		(duplicate_pad_numbers_are_jumpers no)
		(fp_line
			(start 2.750058 0.999998)
			(end -2.750058 0.999998)
			(stroke
				(width 0.1524)
				(type default)
			)
			(layer "F.SilkS")
		)
		(fp_circle
			(center 0 0.999998)
			(end 0 3.750056)
			(stroke
				(width 0.1524)
				(type default)
			)
			(fill no)
			(layer "F.SilkS")
		)
		(fp_poly
			(pts
				(arc
					(start 2.750058 0.999998)
					(mid 0 3.750056)
					(end -2.750058 0.999998)
				)
			)
			(stroke
				(width 0)
				(type default)
			)
			(fill yes)
			(layer "F.SilkS")
		)
		(fp_circle
			(center 0 0.999998)
			(end 0 3.750056)
			(stroke
				(width 0.1)
				(type default)
			)
			(fill no)
			(layer "F.Fab")
		)
		(pad "1" thru_hole rect
			(at 0 0 90)
			(size 1.5748 1.5748)
			(drill 1.0668)
			(layers "*.Cu" "*.Mask")
			(remove_unused_layers no)
			(net "PVCCIN_CPU0")
			(clearance 0)
			(padstack
				(mode front_inner_back)
				(layer "Inner"
					(shape circle)
					(size 1.5748 1.5748)
					(clearance 0)
				)
				(layer "B.Cu"
					(shape rect)
					(size 1.5748 1.5748)
					(clearance 0)
				)
			)
		)
		(pad "2" thru_hole circle
			(at 0 1.999996 90)
			(size 1.5748 1.5748)
			(drill 1.0668)
			(layers "*.Cu" "*.Mask")
			(remove_unused_layers no)
			(net "GND")
			(clearance 0)
		)
	)
	(footprint ""
		(layer "F.Cu")
		(at 54.89956 -165.11397 90)
		(property "Reference" "PU17"
			(at 1.74498 -9.2075 0)
			(unlocked yes)
			(layer "F.SilkS")
			(effects
				(font
					(size 0.7874 0.5842)
					(thickness 0.1524)
				)
				(justify left)
			)
		)
		(property "Value" ""
			(at 0 0 90)
			(layer "F.Fab")
			(effects
				(font
					(size 1.27 1.27)
				)
			)
		)
		(duplicate_pad_numbers_are_jumpers no)
		(fp_line
			(start 2.500122 -2.999994)
			(end 2.500122 -2.44348)
			(stroke
				(width 0.1524)
				(type default)
			)
			(layer "F.SilkS")
		)
		(fp_line
			(start 2.31394 -2.999994)
			(end 2.500122 -2.999994)
			(stroke
				(width 0.1524)
				(type default)
			)
			(layer "F.SilkS")
		)
		(fp_line
			(start -2.500122 -2.999994)
			(end -2.24409 -2.999994)
			(stroke
				(width 0.1524)
				(type default)
			)
			(layer "F.SilkS")
		)
		(fp_line
			(start -2.500122 -2.529078)
			(end -2.500122 -2.999994)
			(stroke
				(width 0.1524)
				(type default)
			)
			(layer "F.SilkS")
		)
		(fp_line
			(start -2.500122 0.6604)
			(end -2.500122 0.229108)
			(stroke
				(width 0.1524)
				(type default)
			)
			(layer "F.SilkS")
		)
		(fp_line
			(start 2.500122 2.339594)
			(end 2.500122 2.999994)
			(stroke
				(width 0.1524)
				(type default)
			)
			(layer "F.SilkS")
		)
		(fp_line
			(start 2.500122 2.999994)
			(end 2.2987 2.999994)
			(stroke
				(width 0.1524)
				(type default)
			)
			(layer "F.SilkS")
		)
		(fp_line
			(start -2.2987 2.999994)
			(end -2.500122 2.999994)
			(stroke
				(width 0.1524)
				(type default)
			)
			(layer "F.SilkS")
		)
		(fp_line
			(start -2.500122 2.999994)
			(end -2.500122 2.339594)
			(stroke
				(width 0.1524)
				(type default)
			)
			(layer "F.SilkS")
		)
		(fp_poly
			(pts
				(xy -5.130292 -2.813558) (xy -5.130292 -1.797558) (xy -4.114292 -2.305558)
			)
			(stroke
				(width 0)
				(type default)
			)
			(fill yes)
			(layer "F.SilkS")
		)
		(fp_line
			(start 2.500122 -2.999994)
			(end 2.500122 2.999994)
			(stroke
				(width 0.1)
				(type default)
			)
			(layer "F.Fab")
		)
		(fp_line
			(start -2.500122 -2.999994)
			(end 2.500122 -2.999994)
			(stroke
				(width 0.1)
				(type default)
			)
			(layer "F.Fab")
		)
		(fp_line
			(start 2.500122 2.999994)
			(end -2.500122 2.999994)
			(stroke
				(width 0.1)
				(type default)
			)
			(layer "F.Fab")
		)
		(fp_line
			(start -2.500122 2.999994)
			(end -2.500122 -2.999994)
			(stroke
				(width 0.1)
				(type default)
			)
			(layer "F.Fab")
		)
		(fp_poly
			(pts
				(xy -4.218432 -2.783078) (xy -4.218432 -1.767078) (xy -3.202432 -2.275078)
			)
			(stroke
				(width 0)
				(type default)
			)
			(fill yes)
			(layer "F.Fab")
		)
		(pad "1" smd rect
			(at -2.400046 -2.275078 180)
			(size 0.2286 0.6096)
			(layers "F.Cu" "F.Mask" "F.Paste")
			(net "PVCCD_HV_CPU1_VOS")
		)
		(pad "2" smd rect
			(at -2.400046 -1.82499 180)
			(size 0.2286 0.6096)
			(layers "F.Cu" "F.Mask" "F.Paste")
			(net "GND")
		)
		(pad "3" smd rect
			(at -2.400046 -1.374902 180)
			(size 0.2286 0.6096)
			(layers "F.Cu" "F.Mask" "F.Paste")
			(net "PVCCD_HV_CPU1_VDD1")
		)
		(pad "4" smd rect
			(at -2.400046 -0.925068 180)
			(size 0.2286 0.6096)
			(layers "F.Cu" "F.Mask" "F.Paste")
			(net "PVCCFA_EHV_CPU1_PVCC")
		)
		(pad "5" smd rect
			(at -2.400046 -0.47498 180)
			(size 0.2286 0.6096)
			(layers "F.Cu" "F.Mask" "F.Paste")
			(net "GND")
		)
		(pad "6" smd rect
			(at -2.400046 -0.024892 180)
			(size 0.2286 0.6096)
			(layers "F.Cu" "F.Mask" "F.Paste")
			(net "Net_1917")
		)
		(pad "7_9-20_24" smd circle
			(at 0 1.150112 180)
			(size 0 0)
			(layers "F.Cu" "F.Mask" "F.Paste")
			(net "GND")
		)
		(pad "10_19" smd rect
			(at 0 2.899918 180)
			(size 0.6096 4.318)
			(layers "F.Cu" "F.Mask" "F.Paste")
			(net "SW_PVCCD_HV_CPU1_SW1")
		)
		(pad "25_29" smd rect
			(at 1.549908 -1.279906)
			(size 2.0574 2.3114)
			(layers "F.Cu" "F.Mask" "F.Paste")
			(net "SW_P12V_PVCCINFAON_CPU1_FLT")
		)
		(pad "30" smd rect
			(at 2.05994 -2.899918 90)
			(size 0.2286 0.6096)
			(layers "F.Cu" "F.Mask" "F.Paste")
			(net "SW_P12V_PVCCINFAON_CPU1_FLT")
		)
		(pad "31" smd rect
			(at 1.610106 -2.899918 90)
			(size 0.2286 0.6096)
			(layers "F.Cu" "F.Mask" "F.Paste")
			(net "Net_1916")
		)
		(pad "32" smd rect
			(at 1.160018 -2.899918 90)
			(size 0.2286 0.6096)
			(layers "F.Cu" "F.Mask" "F.Paste")
			(net "SW_PVCCD_HV_CPU1_BOOTR1")
		)
		(pad "33" smd rect
			(at 0.70993 -2.899918 90)
			(size 0.2286 0.6096)
			(layers "F.Cu" "F.Mask" "F.Paste")
			(net "SW_PVCCD_HV_CPU1_BOOT1")
		)
		(pad "34" smd rect
			(at 0.260096 -2.899918 90)
			(size 0.2286 0.6096)
			(layers "F.Cu" "F.Mask" "F.Paste")
			(net "PVCCD_HV_CPU1_APWM1")
		)
		(pad "35" smd rect
			(at -0.189992 -2.899918 90)
			(size 0.2286 0.6096)
			(layers "F.Cu" "F.Mask" "F.Paste")
			(net "PVCCD_HV_CPU1_VDD1")
		)
		(pad "36" smd rect
			(at -0.64008 -2.899918 90)
			(size 0.2286 0.6096)
			(layers "F.Cu" "F.Mask" "F.Paste")
			(net "PVCCD_HV_CPU1_ATSEN")
		)
		(pad "37" smd rect
			(at -1.089914 -2.899918 90)
			(size 0.2286 0.6096)
			(layers "F.Cu" "F.Mask" "F.Paste")
			(net "PVCCD_HV_CPU1_LSET1")
		)
		(pad "38" smd rect
			(at -1.540002 -2.899918 90)
			(size 0.2286 0.6096)
			(layers "F.Cu" "F.Mask" "F.Paste")
			(net "PVCCD_HV_CPU1_ACSP1")
		)
		(pad "39" smd rect
			(at -1.99009 -2.899918 90)
			(size 0.2286 0.6096)
			(layers "F.Cu" "F.Mask" "F.Paste")
			(net "PVCCD_HV_CPU1_VREF")
		)
		(pad "40" smd rect
			(at -0.87503 -1.27508 90)
			(size 1.7526 1.9558)
			(layers "F.Cu" "F.Mask" "F.Paste")
			(net "GND")
		)
		(pad "41" smd rect
			(at -1.525016 0.249936)
			(size 0.3048 0.4572)
			(layers "F.Cu" "F.Mask" "F.Paste")
			(net "Net_1918")
		)
		(zone
			(layer "F.Cu")
			(hatch none 0.5)
			(connect_pads
				(clearance 0)
			)
			(min_thickness 0.25)
			(keepout
				(tracks not_allowed)
				(vias allowed)
				(pads allowed)
				(copperpour not_allowed)
				(footprints allowed)
			)
			(placement
				(enabled no)
				(sheetname "")
			)
			(fill
				(thermal_gap 0.5)
				(thermal_bridge_width 0.5)
				(island_removal_mode 0)
			)
			(polygon
				(pts
					(xy 57.899554 -162.613848) (xy 57.385966 -162.613848) (xy 57.150254 -162.84956) (xy 57.150254 -167.408606)
					(xy 57.35574 -167.614092) (xy 57.899554 -167.614092) (xy 57.899554 -167.32377) (xy 57.443878 -167.32377)
					(xy 57.443878 -162.90417) (xy 57.899554 -162.90417)
				)
			)
		)
	)
	(footprint ""
		(layer "F.Cu")
		(at 27.628596 -392.326876)
		(property "Reference" "R3267"
			(at 0 0 0)
			(layer "F.SilkS")
			(hide yes)
			(effects
				(font
					(size 1.27 1.27)
				)
			)
		)
		(property "Value" ""
			(at 0 0 0)
			(layer "F.Fab")
			(effects
				(font
					(size 1.27 1.27)
				)
			)
		)
		(duplicate_pad_numbers_are_jumpers no)
		(fp_line
			(start -0.7874 -0.4064)
			(end 0.7874 -0.4064)
			(stroke
				(width 0.1524)
				(type default)
			)
			(layer "F.SilkS")
		)
		(fp_line
			(start -0.7874 0.4064)
			(end -0.7874 -0.4064)
			(stroke
				(width 0.1524)
				(type default)
			)
			(layer "F.SilkS")
		)
		(fp_line
			(start 0.7874 -0.4064)
			(end 0.7874 0.4064)
			(stroke
				(width 0.1524)
				(type default)
			)
			(layer "F.SilkS")
		)
		(fp_line
			(start 0.7874 0.4064)
			(end -0.7874 0.4064)
			(stroke
				(width 0.1524)
				(type default)
			)
			(layer "F.SilkS")
		)
		(fp_line
			(start -0.67945 -0.305054)
			(end -0.12065 -0.305054)
			(stroke
				(width 0.1)
				(type default)
			)
			(layer "F.Fab")
		)
		(fp_line
			(start -0.67945 0.3048)
			(end -0.67945 -0.305054)
			(stroke
				(width 0.1)
				(type default)
			)
			(layer "F.Fab")
		)
		(fp_line
			(start -0.12065 -0.305054)
			(end -0.12065 -0.2794)
			(stroke
				(width 0.1)
				(type default)
			)
			(layer "F.Fab")
		)
		(fp_line
			(start -0.12065 -0.2794)
			(end 0.12065 -0.2794)
			(stroke
				(width 0.1)
				(type default)
			)
			(layer "F.Fab")
		)
		(fp_line
			(start -0.12065 0.2794)
			(end -0.12065 0.3048)
			(stroke
				(width 0.1)
				(type default)
			)
			(layer "F.Fab")
		)
		(fp_line
			(start -0.12065 0.3048)
			(end -0.67945 0.3048)
			(stroke
				(width 0.1)
				(type default)
			)
			(layer "F.Fab")
		)
		(fp_line
			(start 0.120396 0.2794)
			(end -0.12065 0.2794)
			(stroke
				(width 0.1)
				(type default)
			)
			(layer "F.Fab")
		)
		(fp_line
			(start 0.120396 0.3048)
			(end 0.120396 0.2794)
			(stroke
				(width 0.1)
				(type default)
			)
			(layer "F.Fab")
		)
		(fp_line
			(start 0.12065 -0.3048)
			(end 0.67945 -0.3048)
			(stroke
				(width 0.1)
				(type default)
			)
			(layer "F.Fab")
		)
		(fp_line
			(start 0.12065 -0.2794)
			(end 0.12065 -0.3048)
			(stroke
				(width 0.1)
				(type default)
			)
			(layer "F.Fab")
		)
		(fp_line
			(start 0.67945 -0.3048)
			(end 0.67945 0.3048)
			(stroke
				(width 0.1)
				(type default)
			)
			(layer "F.Fab")
		)
		(fp_line
			(start 0.67945 0.3048)
			(end 0.120396 0.3048)
			(stroke
				(width 0.1)
				(type default)
			)
			(layer "F.Fab")
		)
		(pad "1" smd circle
			(at -0.40005 0)
			(size 0 0)
			(layers "F.Cu" "F.Mask" "F.Paste")
			(net "FM_P2E_FGB")
		)
		(pad "2" smd circle
			(at 0.40005 0)
			(size 0 0)
			(layers "F.Cu" "F.Mask" "F.Paste")
			(net "GND")
		)
	)
	(footprint ""
		(layer "F.Cu")
		(at 180.4924 -93.538548 90)
		(property "Reference" "R4579"
			(at 0 0 90)
			(layer "F.SilkS")
			(hide yes)
			(effects
				(font
					(size 1.27 1.27)
				)
			)
		)
		(property "Value" ""
			(at 0 0 90)
			(layer "F.Fab")
			(effects
				(font
					(size 1.27 1.27)
				)
			)
		)
		(duplicate_pad_numbers_are_jumpers no)
		(fp_line
			(start 0.7874 -0.4064)
			(end 0.7874 0.4064)
			(stroke
				(width 0.1524)
				(type default)
			)
			(layer "F.SilkS")
		)
		(fp_line
			(start -0.7874 -0.4064)
			(end 0.7874 -0.4064)
			(stroke
				(width 0.1524)
				(type default)
			)
			(layer "F.SilkS")
		)
		(fp_line
			(start 0.7874 0.4064)
			(end -0.7874 0.4064)
			(stroke
				(width 0.1524)
				(type default)
			)
			(layer "F.SilkS")
		)
		(fp_line
			(start -0.7874 0.4064)
			(end -0.7874 -0.4064)
			(stroke
				(width 0.1524)
				(type default)
			)
			(layer "F.SilkS")
		)
		(fp_line
			(start -0.12065 -0.305054)
			(end -0.12065 -0.2794)
			(stroke
				(width 0.1)
				(type default)
			)
			(layer "F.Fab")
		)
		(fp_line
			(start -0.67945 -0.305054)
			(end -0.12065 -0.305054)
			(stroke
				(width 0.1)
				(type default)
			)
			(layer "F.Fab")
		)
		(fp_line
			(start 0.67945 -0.3048)
			(end 0.67945 0.3048)
			(stroke
				(width 0.1)
				(type default)
			)
			(layer "F.Fab")
		)
		(fp_line
			(start 0.12065 -0.3048)
			(end 0.67945 -0.3048)
			(stroke
				(width 0.1)
				(type default)
			)
			(layer "F.Fab")
		)
		(fp_line
			(start 0.12065 -0.2794)
			(end 0.12065 -0.3048)
			(stroke
				(width 0.1)
				(type default)
			)
			(layer "F.Fab")
		)
		(fp_line
			(start -0.12065 -0.2794)
			(end 0.12065 -0.2794)
			(stroke
				(width 0.1)
				(type default)
			)
			(layer "F.Fab")
		)
		(fp_line
			(start 0.120396 0.2794)
			(end -0.12065 0.2794)
			(stroke
				(width 0.1)
				(type default)
			)
			(layer "F.Fab")
		)
		(fp_line
			(start -0.12065 0.2794)
			(end -0.12065 0.3048)
			(stroke
				(width 0.1)
				(type default)
			)
			(layer "F.Fab")
		)
		(fp_line
			(start 0.67945 0.3048)
			(end 0.120396 0.3048)
			(stroke
				(width 0.1)
				(type default)
			)
			(layer "F.Fab")
		)
		(fp_line
			(start 0.120396 0.3048)
			(end 0.120396 0.2794)
			(stroke
				(width 0.1)
				(type default)
			)
			(layer "F.Fab")
		)
		(fp_line
			(start -0.12065 0.3048)
			(end -0.67945 0.3048)
			(stroke
				(width 0.1)
				(type default)
			)
			(layer "F.Fab")
		)
		(fp_line
			(start -0.67945 0.3048)
			(end -0.67945 -0.305054)
			(stroke
				(width 0.1)
				(type default)
			)
			(layer "F.Fab")
		)
		(pad "1" smd rect
			(at -0.40005 0 270)
			(size 0.4572 0.508)
			(layers "F.Cu" "F.Mask" "F.Paste")
			(net "P3V3_AUX")
		)
		(pad "2" smd rect
			(at 0.40005 0 270)
			(size 0.4572 0.508)
			(layers "F.Cu" "F.Mask" "F.Paste")
			(net "FAB_BMC_REV_ID0")
		)
	)
)
